FILE_TYPE = MACRO_DRAWING;
SET COLOR_WIRE YELLOW;
SET COLOR_PROP ORANGE;
SET COLOR_DOT WHITE;
SET COLOR_ARC YELLOW;
SET COLOR_BODY GREEN;
SET COLOR_NOTE PURPLE;
SET PROP_DISPLAY VALUE;
SET PAGE_NUMBER P26;
FORCEADD OFFPAGE..2
(-2475 4750);
FORCEPROP 2 LAST $XR0 53 
J 0
(-2286 4750);
DISPLAY 0.638298 (-2286 4750);
PAINT MONO (-2286 4750);
FORCEPROP 2 LAST CDS_LIB standard
J 0
(-2475 4750);
DISPLAY INVISIBLE (-2475 4750);
FORCEPROP 1 LAST OFFPAGE TRUE
J 0
(-2150 4625);
DISPLAY 0.872340 (-2150 4625);
PAINT GREEN (-2150 4625);
DISPLAY INVISIBLE (-2150 4625);
FORCEPROP 1 LAST COMMENT_BODY TRUE
J 0
(-2520 4655);
DISPLAY 0.872340 (-2520 4655);
PAINT GREEN (-2520 4655);
DISPLAY INVISIBLE (-2520 4655);
FORCEPROP 2 LAST PATH I104
J 0
(-2275 4800);
DISPLAY 1.021277 (-2275 4800);
DISPLAY INVISIBLE (-2275 4800);
FORCEADD OFFPAGE..2
(-2475 4700);
FORCEPROP 2 LAST $XR0 53 
J 0
(-2286 4700);
DISPLAY 0.638298 (-2286 4700);
PAINT MONO (-2286 4700);
FORCEPROP 2 LAST CDS_LIB standard
J 0
(-2475 4700);
DISPLAY INVISIBLE (-2475 4700);
FORCEPROP 1 LAST OFFPAGE TRUE
J 0
(-2150 4575);
DISPLAY 0.872340 (-2150 4575);
PAINT GREEN (-2150 4575);
DISPLAY INVISIBLE (-2150 4575);
FORCEPROP 1 LAST COMMENT_BODY TRUE
J 0
(-2520 4605);
DISPLAY 0.872340 (-2520 4605);
PAINT GREEN (-2520 4605);
DISPLAY INVISIBLE (-2520 4605);
FORCEPROP 2 LAST PATH I105
J 0
(-2275 4750);
DISPLAY 1.021277 (-2275 4750);
DISPLAY INVISIBLE (-2275 4750);
FORCEADD GENOA_SP5..19
(-4575 4800);
FORCEPROP 1 LAST LOCATION U25
J 0
(-5375 5650);
DISPLAY 0.489362 (-5375 5650);
PAINT SKYBLUE (-5375 5650);
FORCEPROP 0 LAST $SEC 19
J 0
(-5350 5675);
DISPLAY 0.680851 (-5350 5675);
PAINT MONO (-5350 5675);
DISPLAY INVISIBLE (-5350 5675);
FORCEPROP 0 LAST CDS_SEC 19
J 0
(-5375 5675);
DISPLAY 1.021277 (-5375 5675);
DISPLAY INVISIBLE (-5375 5675);
FORCEPROP 0 LASTPIN (-5525 5150) $PN DG53
J 2
(-5535 5160);
DISPLAY 0.489362 (-5535 5160);
PAINT MONO (-5535 5160);
FORCEPROP 0 LASTPIN (-5525 5050) $PN DG50
J 2
(-5535 5060);
DISPLAY 0.489362 (-5535 5060);
PAINT MONO (-5535 5060);
FORCEPROP 0 LASTPIN (-5525 4950) $PN DG47
J 2
(-5535 4960);
DISPLAY 0.489362 (-5535 4960);
PAINT MONO (-5535 4960);
FORCEPROP 0 LASTPIN (-5525 4850) $PN DG44
J 2
(-5535 4860);
DISPLAY 0.489362 (-5535 4860);
PAINT MONO (-5535 4860);
FORCEPROP 0 LASTPIN (-5525 5200) $PN DG54
J 2
(-5535 5210);
DISPLAY 0.489362 (-5535 5210);
PAINT MONO (-5535 5210);
FORCEPROP 0 LASTPIN (-5525 5100) $PN DG51
J 2
(-5535 5110);
DISPLAY 0.489362 (-5535 5110);
PAINT MONO (-5535 5110);
FORCEPROP 0 LASTPIN (-5525 5000) $PN DG48
J 2
(-5535 5010);
DISPLAY 0.489362 (-5535 5010);
PAINT MONO (-5535 5010);
FORCEPROP 0 LASTPIN (-5525 4900) $PN DG45
J 2
(-5535 4910);
DISPLAY 0.489362 (-5535 4910);
PAINT MONO (-5535 4910);
FORCEPROP 0 LASTPIN (-3625 5150) $PN DE52
J 0
(-3615 5160);
DISPLAY 0.489362 (-3615 5160);
PAINT MONO (-3615 5160);
FORCEPROP 0 LASTPIN (-3625 5050) $PN DE49
J 0
(-3615 5060);
DISPLAY 0.489362 (-3615 5060);
PAINT MONO (-3615 5060);
FORCEPROP 0 LASTPIN (-3625 4950) $PN DE46
J 0
(-3615 4960);
DISPLAY 0.489362 (-3615 4960);
PAINT MONO (-3615 4960);
FORCEPROP 0 LASTPIN (-3625 4850) $PN DE43
J 0
(-3615 4860);
DISPLAY 0.489362 (-3615 4860);
PAINT MONO (-3615 4860);
FORCEPROP 0 LASTPIN (-3625 5200) $PN DE53
J 0
(-3615 5210);
DISPLAY 0.489362 (-3615 5210);
PAINT MONO (-3615 5210);
FORCEPROP 0 LASTPIN (-3625 5100) $PN DE50
J 0
(-3615 5110);
DISPLAY 0.489362 (-3615 5110);
PAINT MONO (-3615 5110);
FORCEPROP 0 LASTPIN (-3625 5000) $PN DE47
J 0
(-3615 5010);
DISPLAY 0.489362 (-3615 5010);
PAINT MONO (-3615 5010);
FORCEPROP 0 LASTPIN (-3625 4900) $PN DE44
J 0
(-3615 4910);
DISPLAY 0.489362 (-3615 4910);
PAINT MONO (-3615 4910);
FORCEPROP 0 LASTPIN (-5525 4400) $PN E44
J 2
(-5535 4410);
DISPLAY 0.489362 (-5535 4410);
PAINT MONO (-5535 4410);
FORCEPROP 0 LASTPIN (-5525 4300) $PN E41
J 2
(-5535 4310);
DISPLAY 0.489362 (-5535 4310);
PAINT MONO (-5535 4310);
FORCEPROP 0 LASTPIN (-5525 4450) $PN E43
J 2
(-5535 4460);
DISPLAY 0.489362 (-5535 4460);
PAINT MONO (-5535 4460);
FORCEPROP 0 LASTPIN (-5525 4350) $PN E40
J 2
(-5535 4360);
DISPLAY 0.489362 (-5535 4360);
PAINT MONO (-5535 4360);
FORCEPROP 0 LASTPIN (-3625 4400) $PN C45
J 0
(-3615 4410);
DISPLAY 0.489362 (-3615 4410);
PAINT MONO (-3615 4410);
FORCEPROP 0 LASTPIN (-3625 4300) $PN C42
J 0
(-3615 4310);
DISPLAY 0.489362 (-3615 4310);
PAINT MONO (-3615 4310);
FORCEPROP 0 LASTPIN (-3625 4450) $PN C44
J 0
(-3615 4460);
DISPLAY 0.489362 (-3615 4460);
PAINT MONO (-3615 4460);
FORCEPROP 0 LASTPIN (-3625 4350) $PN C41
J 0
(-3615 4360);
DISPLAY 0.489362 (-3615 4360);
PAINT MONO (-3615 4360);
FORCEPROP 0 LASTPIN (-5525 4700) $PN E50
J 2
(-5535 4710);
DISPLAY 0.489362 (-5535 4710);
PAINT MONO (-5535 4710);
FORCEPROP 0 LASTPIN (-5525 4600) $PN E47
J 2
(-5535 4610);
DISPLAY 0.489362 (-5535 4610);
PAINT MONO (-5535 4610);
FORCEPROP 0 LASTPIN (-5525 4750) $PN E49
J 2
(-5535 4760);
DISPLAY 0.489362 (-5535 4760);
PAINT MONO (-5535 4760);
FORCEPROP 0 LASTPIN (-5525 4650) $PN E46
J 2
(-5535 4660);
DISPLAY 0.489362 (-5535 4660);
PAINT MONO (-5535 4660);
FORCEPROP 0 LASTPIN (-3625 4700) $PN C51
J 0
(-3615 4710);
DISPLAY 0.489362 (-3615 4710);
PAINT MONO (-3615 4710);
FORCEPROP 0 LASTPIN (-3625 4600) $PN C48
J 0
(-3615 4610);
DISPLAY 0.489362 (-3615 4610);
PAINT MONO (-3615 4610);
FORCEPROP 0 LASTPIN (-3625 4750) $PN C50
J 0
(-3615 4760);
DISPLAY 0.489362 (-3615 4760);
PAINT MONO (-3615 4760);
FORCEPROP 0 LASTPIN (-3625 4650) $PN C47
J 0
(-3615 4660);
DISPLAY 0.489362 (-3615 4660);
PAINT MONO (-3615 4660);
FORCEPROP 2 LAST PART_TYPE SMLF
J 0
(-5375 5575);
DISPLAY 1.021277 (-5375 5575);
FORCEPROP 1 LAST MATERIAL IO
J 0
(-5370 5432);
DISPLAY 0.489362 (-5370 5432);
PAINT SKYBLUE (-5370 5432);
FORCEPROP 2 LAST VALUE SOCKET6096_13568-001
J 0
(-5375 5475);
DISPLAY 0.489362 (-5375 5475);
PAINT SKYBLUE (-5375 5475);
FORCEPROP 1 LAST PART_NUMBER DGA^6000030
J 0
(-5375 5525);
DISPLAY 0.489362 (-5375 5525);
PAINT SKYBLUE (-5375 5525);
FORCEPROP 1 LAST CDS_LMAN_SYM_OUTLINE -800,600,800,-600
J 0
(-4575 4800);
DISPLAY 0.468085 (-4575 4800);
PAINT GREEN (-4575 4800);
DISPLAY INVISIBLE (-4575 4800);
FORCEPROP 1 LAST NEEDS_NO_SIZE TRUE
J 0
(-4575 4800);
DISPLAY 0.723404 (-4575 4800);
PAINT GREEN (-4575 4800);
DISPLAY INVISIBLE (-4575 4800);
FORCEPROP 2 LAST CDS_LIB pure_quanta
J 0
(-4575 4800);
DISPLAY INVISIBLE (-4575 4800);
FORCEPROP 1 LAST PATH I59
J 0
(-4575 4800);
DISPLAY 0.723404 (-4575 4800);
PAINT GREEN (-4575 4800);
DISPLAY INVISIBLE (-4575 4800);
FORCEADD OFFPAGE..4
R 2
(-6675 4750);
FORCEPROP 2 LAST $XR0 53 
J 0
(-6926 4750);
DISPLAY 0.638298 (-6926 4750);
PAINT MONO (-6926 4750);
FORCEPROP 2 LAST CDS_LIB standard
J 0
(-6675 4750);
DISPLAY INVISIBLE (-6675 4750);
FORCEPROP 1 LAST OFFPAGE TRUE
J 2
(-7000 4625);
DISPLAY 0.872340 (-7000 4625);
PAINT GREEN (-7000 4625);
DISPLAY INVISIBLE (-7000 4625);
FORCEPROP 1 LAST COMMENT_BODY TRUE
J 2
(-6650 4650);
DISPLAY 0.872340 (-6650 4650);
PAINT GREEN (-6650 4650);
DISPLAY INVISIBLE (-6650 4650);
FORCEPROP 2 LAST PATH I86
J 0
(-6925 4800);
DISPLAY 1.021277 (-6925 4800);
DISPLAY INVISIBLE (-6925 4800);
FORCEADD OFFPAGE..4
R 2
(-6675 4700);
FORCEPROP 2 LAST $XR0 53 
J 0
(-6926 4700);
DISPLAY 0.638298 (-6926 4700);
PAINT MONO (-6926 4700);
FORCEPROP 2 LAST CDS_LIB standard
J 0
(-6675 4700);
DISPLAY INVISIBLE (-6675 4700);
FORCEPROP 1 LAST OFFPAGE TRUE
J 2
(-7000 4575);
DISPLAY 0.872340 (-7000 4575);
PAINT GREEN (-7000 4575);
DISPLAY INVISIBLE (-7000 4575);
FORCEPROP 1 LAST COMMENT_BODY TRUE
J 2
(-6650 4600);
DISPLAY 0.872340 (-6650 4600);
PAINT GREEN (-6650 4600);
DISPLAY INVISIBLE (-6650 4600);
FORCEPROP 2 LAST PATH I87
J 0
(-6925 4750);
DISPLAY 1.021277 (-6925 4750);
DISPLAY INVISIBLE (-6925 4750);
FORCEADD QUANTA_TITLE_BLOCK_C..1
(0 0);
FORCEPROP 0 LAST CDS_CON_LAST_MODIFIED Fri Mar 11 14:52:20 2022
J 0
(-1885 15);
DISPLAY INVISIBLE (-1885 15);
FORCEPROP 1 LAST CUSTOM_TXT_CDS <CON_LAST_MODIFIED>
J 0
(-1885 15);
DISPLAY 0.978723 (-1885 15);
FORCEPROP 2 LAST CUSTOM_TXT_CDS <XR_PAGE_TITLE>
J 0
(-7890 5250);
DISPLAY 0.638298 (-7890 5250);
PAINT PINK (-7890 5250);
DISPLAY INVISIBLE (-7890 5250);
FORCEPROP 1 LAST CUSTOM_TXT_CDS <NAME_2>
J 0
(-3175 50);
FORCEPROP 1 LAST CUSTOM_TXT_CDS <NAME_1>
J 0
(-3175 175);
FORCEPROP 1 LAST CUSTOM_TXT_CDS <Q_NUMBER>
J 0
(-1403 103);
DISPLAY 1.212766 (-1403 103);
FORCEPROP 1 LAST CUSTOM_TXT_CDS <Q_PROJ>
J 0
(-2382 102);
DISPLAY 1.212766 (-2382 102);
FORCEPROP 1 LAST CUSTOM_TXT_CDS <Q_REV>
J 0
(-184 103);
DISPLAY 1.212766 (-184 103);
FORCEPROP 1 LAST CUSTOM_TXT_CDS <CON_PAGE_NUM> OF <CON_TOTAL_PAGES>
J 0
(-446 18);
DISPLAY 0.978723 (-446 18);
FORCEPROP 1 LAST Q_TITLE CPU0 PCIE P4/P5/WAFL
J 0
(-9366 26);
DISPLAY 2.446809 (-9366 26);
PAINT GREEN (-9366 26);
FORCEPROP 1 LAST Q_DEPT BU9
J 1
(-3763 49);
DISPLAY 1.957447 (-3763 49);
PAINT GREEN (-3763 49);
FORCEPROP 1 LAST CDS_LMAN_SYM_OUTLINE -9475,6775,100,-125
J 0
(0 0);
DISPLAY 0.468085 (0 0);
PAINT GREEN (0 0);
DISPLAY INVISIBLE (0 0);
FORCEPROP 2 LAST CDS_LIB pure_quanta
J 0
(0 0);
DISPLAY INVISIBLE (0 0);
FORCEPROP 2 LAST PAGE_BORDER TRUE
J 0
(-7890 5250);
DISPLAY 0.638298 (-7890 5250);
PAINT PINK (-7890 5250);
DISPLAY INVISIBLE (-7890 5250);
FORCEPROP 1 LAST COMMENT_BODY TRUE
J 0
(12 -13);
DISPLAY 0.978723 (12 -13);
PAINT GREEN (12 -13);
DISPLAY INVISIBLE (12 -13);
FORCEPROP 2 LAST CDS_XR_PAGE_TITLE CR-26 : @T6G_MB_LIB.T6G(SCH_1):PAGE26
J 0
(-7890 5250);
DISPLAY 0.638298 (-7890 5250);
PAINT PINK (-7890 5250);
DISPLAY INVISIBLE (-7890 5250);
WIRE 16 -1 (-6625 4700)(-5525 4700);
FORCEPROP 2 LAST SIG_NAME WAFL_CPU1_TX1_CPU0_RX0_DN
J 0
(-6535 4710);
DISPLAY 0.489362 (-6535 4710);
FORCEPROP 0 LAST $PHYS_NET_NAME P3E_M2_0_SATA_RX_DP
J 0
(-6435 4739);
DISPLAY INVISIBLE (-6435 4739);
WIRE 16 -1 (-6625 4750)(-5525 4750);
FORCEPROP 2 LAST SIG_NAME WAFL_CPU1_TX1_CPU0_RX0_DP
J 0
(-6535 4760);
DISPLAY 0.489362 (-6535 4760);
WIRE 16 -1 (-3625 4700)(-2525 4700);
FORCEPROP 2 LAST SIG_NAME WAFL_CPU0_TX0_CPU1_RX1_DN
J 0
(-3360 4710);
DISPLAY 0.489362 (-3360 4710);
FORCEPROP 0 LAST $PHYS_NET_NAME P3E_M2_0_SATA_RX_DP
J 0
(-3435 4739);
DISPLAY INVISIBLE (-3435 4739);
WIRE 16 -1 (-3625 4750)(-2525 4750);
FORCEPROP 2 LAST SIG_NAME WAFL_CPU0_TX0_CPU1_RX1_DP
J 0
(-3360 4760);
DISPLAY 0.489362 (-3360 4760);
QUIT
